(kicad_pcb
	(version 20260206)
	(generator "pcbnew")
	(generator_version "10.0")
	(general
		(thickness 1.6)
		(legacy_teardrops no)
	)
	(paper "A4")
	(title_block
		(title "panther-plus-userver — 13130-1b_20150205.brd")
		(comment 1 "Honey Badger (Wiwynn) / footprints 459-466 of 1509")
	)
	(layers
		(0 "F.Cu" signal "TOP")
		(4 "In1.Cu" signal "L2")
		(6 "In2.Cu" signal "L3")
		(8 "In3.Cu" signal "L4")
		(10 "In4.Cu" signal "L5")
		(12 "In5.Cu" signal "L6")
		(14 "In6.Cu" signal "L7")
		(16 "In7.Cu" signal "L8")
		(18 "In8.Cu" signal "L9")
		(20 "In9.Cu" signal "L10")
		(22 "In10.Cu" signal "L11")
		(2 "B.Cu" signal "BOTTOM")
		(9 "F.Adhes" user "F.Adhesive")
		(11 "B.Adhes" user "B.Adhesive")
		(13 "F.Paste" user "Package Geometry/Pastemask Top")
		(15 "B.Paste" user "Package Geometry/Pastemask Bottom")
		(5 "F.SilkS" user "Ref Des/Silkscreen Top")
		(7 "B.SilkS" user "Ref Des/Silkscreen Bottom")
		(1 "F.Mask" user "Board Geometry/Soldermask Top")
		(3 "B.Mask" user "Board Geometry/Soldermask Bottom")
		(17 "Dwgs.User" user "User.Drawings")
		(19 "Cmts.User" user "User.Comments")
		(21 "Eco1.User" user "User.Eco1")
		(23 "Eco2.User" user "User.Eco2")
		(25 "Edge.Cuts" user "Board Geometry/Outline")
		(27 "Margin" user)
		(31 "F.CrtYd" user "Package Geometry/Place Bound Top")
		(29 "B.CrtYd" user "Package Geometry/Place Bound Bottom")
		(35 "F.Fab" user "Ref Des/Assembly Top")
		(33 "B.Fab" user "Ref Des/Assembly Bottom")
	)
	(footprint ""
		(layer "F.Cu")
		(at 17.8308 -67.1322)
		(property "Reference" "PC9"
			(at 0 0 0)
			(layer "F.SilkS")
			(hide yes)
			(effects
				(font
					(size 1.27 1.27)
				)
			)
		)
		(property "Value" "SCD1U16V2KX-3GP"
			(at 1.8923 -1.2065 0)
			(unlocked yes)
			(layer "F.Fab")
			(hide yes)
			(effects
				(font
					(size 1.016 1.016)
					(thickness 0.1524)
				)
			)
		)
		(property "Device Type" "C402H22"
			(at 1.8923 -2.7305 0)
			(unlocked yes)
			(layer "F.Fab")
			(hide yes)
			(effects
				(font
					(size 1.016 1.016)
					(thickness 0.1524)
				)
			)
		)
		(duplicate_pad_numbers_are_jumpers no)
		(fp_rect
			(start -0.381 0.7366)
			(end 0.381 -0.7366)
			(stroke
				(width 0)
				(type default)
			)
			(fill no)
			(layer "F.CrtYd")
		)
		(fp_rect
			(start -0.381 0.7366)
			(end 0.381 -0.7366)
			(stroke
				(width 0)
				(type default)
			)
			(fill no)
			(layer "F.Fab")
		)
		(pad "1" smd custom
			(at 0 -0.4572)
			(size 0.1143 0.1143)
			(layers "F.Cu" "F.Mask" "F.Paste")
			(net "GND")
			(options
				(clearance outline)
				(anchor circle)
			)
			(primitives
				(gr_poly
					(pts
						(arc
							(start -0.254 -0.1778)
							(mid -0.239121 -0.213721)
							(end -0.2032 -0.2286)
						)
						(arc
							(start 0.2032 -0.2286)
							(mid 0.239121 -0.213721)
							(end 0.254 -0.1778)
						)
						(arc
							(start 0.254 0.1778)
							(mid 0.239121 0.213721)
							(end 0.2032 0.2286)
						)
						(arc
							(start -0.2032 0.2286)
							(mid -0.239121 0.213721)
							(end -0.254 0.1778)
						)
					)
					(width 0)
					(fill yes)
				)
			)
		)
		(pad "2" smd custom
			(at 0 0.4572)
			(size 0.1143 0.1143)
			(layers "F.Cu" "F.Mask" "F.Paste")
			(net "VR_PVNN_ISUMN")
			(options
				(clearance outline)
				(anchor circle)
			)
			(primitives
				(gr_poly
					(pts
						(arc
							(start -0.254 -0.1778)
							(mid -0.239121 -0.213721)
							(end -0.2032 -0.2286)
						)
						(arc
							(start 0.2032 -0.2286)
							(mid 0.239121 -0.213721)
							(end 0.254 -0.1778)
						)
						(arc
							(start 0.254 0.1778)
							(mid 0.239121 0.213721)
							(end 0.2032 0.2286)
						)
						(arc
							(start -0.2032 0.2286)
							(mid -0.239121 0.213721)
							(end -0.254 0.1778)
						)
					)
					(width 0)
					(fill yes)
				)
			)
		)
	)
	(footprint ""
		(layer "F.Cu")
		(at 8.509 -58.293 90)
		(property "Reference" "C42"
			(at 0 0 90)
			(layer "F.SilkS")
			(hide yes)
			(effects
				(font
					(size 1.27 1.27)
				)
			)
		)
		(property "Value" "SCD1U16V2KX-3GP"
			(at 1.1811 -2.7051 90)
			(unlocked yes)
			(layer "F.Fab")
			(hide yes)
			(effects
				(font
					(size 1.016 1.016)
					(thickness 0.1524)
				)
			)
		)
		(property "Device Type" "C402H22"
			(at 1.1811 -4.2291 90)
			(unlocked yes)
			(layer "F.Fab")
			(hide yes)
			(effects
				(font
					(size 1.016 1.016)
					(thickness 0.1524)
				)
			)
		)
		(duplicate_pad_numbers_are_jumpers no)
		(fp_rect
			(start -0.381 0.7366)
			(end 0.381 -0.7366)
			(stroke
				(width 0)
				(type default)
			)
			(fill no)
			(layer "F.CrtYd")
		)
		(fp_rect
			(start -0.381 0.7366)
			(end 0.381 -0.7366)
			(stroke
				(width 0)
				(type default)
			)
			(fill no)
			(layer "F.Fab")
		)
		(pad "1" smd custom
			(at 0 -0.4572 90)
			(size 0.1143 0.1143)
			(layers "F.Cu" "F.Mask" "F.Paste")
			(net "P2E_CPU_NGFF_C_RX_DN13")
			(options
				(clearance outline)
				(anchor circle)
			)
			(primitives
				(gr_poly
					(pts
						(arc
							(start -0.254 -0.1778)
							(mid -0.239121 -0.213721)
							(end -0.2032 -0.2286)
						)
						(arc
							(start 0.2032 -0.2286)
							(mid 0.239121 -0.213721)
							(end 0.254 -0.1778)
						)
						(arc
							(start 0.254 0.1778)
							(mid 0.239121 0.213721)
							(end 0.2032 0.2286)
						)
						(arc
							(start -0.2032 0.2286)
							(mid -0.239121 0.213721)
							(end -0.254 0.1778)
						)
					)
					(width 0)
					(fill yes)
				)
			)
		)
		(pad "2" smd custom
			(at 0 0.4572 90)
			(size 0.1143 0.1143)
			(layers "F.Cu" "F.Mask" "F.Paste")
			(net "P2E_CPU_NGFF_RX_DN13")
			(options
				(clearance outline)
				(anchor circle)
			)
			(primitives
				(gr_poly
					(pts
						(arc
							(start -0.254 -0.1778)
							(mid -0.239121 -0.213721)
							(end -0.2032 -0.2286)
						)
						(arc
							(start 0.2032 -0.2286)
							(mid 0.239121 -0.213721)
							(end 0.254 -0.1778)
						)
						(arc
							(start 0.254 0.1778)
							(mid 0.239121 0.213721)
							(end 0.2032 0.2286)
						)
						(arc
							(start -0.2032 0.2286)
							(mid -0.239121 0.213721)
							(end -0.254 0.1778)
						)
					)
					(width 0)
					(fill yes)
				)
			)
		)
	)
	(footprint ""
		(layer "F.Cu")
		(at 5.08 -32.258)
		(property "Reference" "PR209"
			(at 0 0 0)
			(layer "F.SilkS")
			(hide yes)
			(effects
				(font
					(size 1.27 1.27)
				)
			)
		)
		(property "Value" "2D2R3J-2-GP"
			(at -0.0254 -2.0193 0)
			(unlocked yes)
			(layer "F.Fab")
			(hide yes)
			(effects
				(font
					(size 1.016 1.016)
					(thickness 0.1524)
				)
			)
		)
		(property "Device Type" "R603H22"
			(at -0.0254 -3.5433 0)
			(unlocked yes)
			(layer "F.Fab")
			(hide yes)
			(effects
				(font
					(size 1.016 1.016)
					(thickness 0.1524)
				)
			)
		)
		(duplicate_pad_numbers_are_jumpers no)
		(fp_line
			(start -0.2032 0)
			(end -0.4191 0)
			(stroke
				(width 0.2032)
				(type default)
			)
			(layer "F.SilkS")
		)
		(fp_line
			(start 0.4318 0)
			(end 0.2032 0)
			(stroke
				(width 0.2032)
				(type default)
			)
			(layer "F.SilkS")
		)
		(fp_rect
			(start -0.635 1.1811)
			(end 0.635 -1.1811)
			(stroke
				(width 0)
				(type default)
			)
			(fill no)
			(layer "F.CrtYd")
		)
		(fp_rect
			(start -0.635 1.1811)
			(end 0.635 -1.1811)
			(stroke
				(width 0)
				(type default)
			)
			(fill no)
			(layer "F.Fab")
		)
		(pad "1" smd custom
			(at 0 -0.6604)
			(size 0.19685 0.19685)
			(layers "F.Cu" "F.Mask" "F.Paste")
			(net "P3V3_STBY_VDD")
			(options
				(clearance outline)
				(anchor circle)
			)
			(primitives
				(gr_poly
					(pts
						(arc
							(start 0.508 -0.2921)
							(mid 0.478242 -0.363942)
							(end 0.4064 -0.3937)
						)
						(arc
							(start -0.4064 -0.3937)
							(mid -0.478242 -0.363942)
							(end -0.508 -0.2921)
						)
						(arc
							(start -0.508 0.2921)
							(mid -0.478242 0.363942)
							(end -0.4064 0.3937)
						)
						(arc
							(start 0.4064 0.3937)
							(mid 0.478242 0.363942)
							(end 0.508 0.2921)
						)
					)
					(width 0)
					(fill yes)
				)
			)
		)
		(pad "2" smd custom
			(at 0 0.6604)
			(size 0.19685 0.19685)
			(layers "F.Cu" "F.Mask" "F.Paste")
			(net "P12V")
			(options
				(clearance outline)
				(anchor circle)
			)
			(primitives
				(gr_poly
					(pts
						(arc
							(start 0.508 -0.2921)
							(mid 0.478242 -0.363942)
							(end 0.4064 -0.3937)
						)
						(arc
							(start -0.4064 -0.3937)
							(mid -0.478242 -0.363942)
							(end -0.508 -0.2921)
						)
						(arc
							(start -0.508 0.2921)
							(mid -0.478242 0.363942)
							(end -0.4064 0.3937)
						)
						(arc
							(start 0.4064 0.3937)
							(mid 0.478242 0.363942)
							(end 0.508 0.2921)
						)
					)
					(width 0)
					(fill yes)
				)
			)
		)
	)
	(footprint ""
		(layer "F.Cu")
		(at 111.633 -57.912 90)
		(property "Reference" "R24"
			(at 0 0 90)
			(layer "F.SilkS")
			(hide yes)
			(effects
				(font
					(size 1.27 1.27)
				)
			)
		)
		(property "Value" "100R2F-L1-GP-U"
			(at 0.064008 -3.993896 90)
			(unlocked yes)
			(layer "F.Fab")
			(hide yes)
			(effects
				(font
					(size 1.016 1.016)
					(thickness 0.1524)
				)
			)
		)
		(property "Device Type" "R402H14"
			(at 0.064008 -5.517896 90)
			(unlocked yes)
			(layer "F.Fab")
			(hide yes)
			(effects
				(font
					(size 1.016 1.016)
					(thickness 0.1524)
				)
			)
		)
		(duplicate_pad_numbers_are_jumpers no)
		(fp_rect
			(start -0.381 0.8382)
			(end 0.381 -0.8382)
			(stroke
				(width 0)
				(type default)
			)
			(fill no)
			(layer "F.CrtYd")
		)
		(fp_rect
			(start -0.381 0.8382)
			(end 0.381 -0.8382)
			(stroke
				(width 0)
				(type default)
			)
			(fill no)
			(layer "F.Fab")
		)
		(pad "1" smd custom
			(at 0 -0.4318 90)
			(size 0.127 0.127)
			(layers "F.Cu" "F.Mask" "F.Paste")
			(net "M_A_MON2_P")
			(options
				(clearance outline)
				(anchor circle)
			)
			(primitives
				(gr_poly
					(pts
						(arc
							(start -0.2032 -0.2794)
							(mid -0.239121 -0.264521)
							(end -0.254 -0.2286)
						)
						(arc
							(start -0.254 0.2286)
							(mid -0.239121 0.264521)
							(end -0.2032 0.2794)
						)
						(arc
							(start 0.2032 0.2794)
							(mid 0.239121 0.264521)
							(end 0.254 0.2286)
						)
						(arc
							(start 0.254 -0.2286)
							(mid 0.239121 -0.264521)
							(end 0.2032 -0.2794)
						)
					)
					(width 0)
					(fill yes)
				)
			)
		)
		(pad "2" smd custom
			(at 0 0.4318 90)
			(size 0.127 0.127)
			(layers "F.Cu" "F.Mask" "F.Paste")
			(net "M_A_MON2_N")
			(options
				(clearance outline)
				(anchor circle)
			)
			(primitives
				(gr_poly
					(pts
						(arc
							(start -0.2032 -0.2794)
							(mid -0.239121 -0.264521)
							(end -0.254 -0.2286)
						)
						(arc
							(start -0.254 0.2286)
							(mid -0.239121 0.264521)
							(end -0.2032 0.2794)
						)
						(arc
							(start 0.2032 0.2794)
							(mid 0.239121 0.264521)
							(end 0.254 0.2286)
						)
						(arc
							(start 0.254 -0.2286)
							(mid 0.239121 -0.264521)
							(end 0.2032 -0.2794)
						)
					)
					(width 0)
					(fill yes)
				)
			)
		)
	)
	(footprint ""
		(layer "F.Cu")
		(at 163.83 -42.418)
		(property "Reference" "R75"
			(at 0 0 0)
			(layer "F.SilkS")
			(hide yes)
			(effects
				(font
					(size 1.27 1.27)
				)
			)
		)
		(property "Value" "10KR2F-2-GP"
			(at 0.064008 -3.993896 0)
			(unlocked yes)
			(layer "F.Fab")
			(hide yes)
			(effects
				(font
					(size 1.016 1.016)
					(thickness 0.1524)
				)
			)
		)
		(property "Device Type" "R402H16"
			(at 0.064008 -5.517896 0)
			(unlocked yes)
			(layer "F.Fab")
			(hide yes)
			(effects
				(font
					(size 1.016 1.016)
					(thickness 0.1524)
				)
			)
		)
		(duplicate_pad_numbers_are_jumpers no)
		(fp_rect
			(start -0.381 0.8382)
			(end 0.381 -0.8382)
			(stroke
				(width 0)
				(type default)
			)
			(fill no)
			(layer "F.CrtYd")
		)
		(fp_rect
			(start -0.381 0.8382)
			(end 0.381 -0.8382)
			(stroke
				(width 0)
				(type default)
			)
			(fill no)
			(layer "F.Fab")
		)
		(pad "1" smd custom
			(at 0 -0.4318)
			(size 0.127 0.127)
			(layers "F.Cu" "F.Mask" "F.Paste")
			(net "P3V3_STBY")
			(options
				(clearance outline)
				(anchor circle)
			)
			(primitives
				(gr_poly
					(pts
						(arc
							(start -0.2032 -0.2794)
							(mid -0.239121 -0.264521)
							(end -0.254 -0.2286)
						)
						(arc
							(start -0.254 0.2286)
							(mid -0.239121 0.264521)
							(end -0.2032 0.2794)
						)
						(arc
							(start 0.2032 0.2794)
							(mid 0.239121 0.264521)
							(end 0.254 0.2286)
						)
						(arc
							(start 0.254 -0.2286)
							(mid 0.239121 -0.264521)
							(end 0.2032 -0.2794)
						)
					)
					(width 0)
					(fill yes)
				)
			)
		)
		(pad "2" smd custom
			(at 0 0.4318)
			(size 0.127 0.127)
			(layers "F.Cu" "F.Mask" "F.Paste")
			(net "OSC_5M_EN")
			(options
				(clearance outline)
				(anchor circle)
			)
			(primitives
				(gr_poly
					(pts
						(arc
							(start -0.2032 -0.2794)
							(mid -0.239121 -0.264521)
							(end -0.254 -0.2286)
						)
						(arc
							(start -0.254 0.2286)
							(mid -0.239121 0.264521)
							(end -0.2032 0.2794)
						)
						(arc
							(start 0.2032 0.2794)
							(mid 0.239121 0.264521)
							(end 0.254 0.2286)
						)
						(arc
							(start 0.254 -0.2286)
							(mid 0.239121 -0.264521)
							(end 0.2032 -0.2794)
						)
					)
					(width 0)
					(fill yes)
				)
			)
		)
	)
	(footprint ""
		(layer "F.Cu")
		(at 67.818 -21.082 180)
		(property "Reference" "R157"
			(at 0 0 180)
			(layer "F.SilkS")
			(hide yes)
			(effects
				(font
					(size 1.27 1.27)
				)
			)
		)
		(property "Value" "4K7R2F-GP"
			(at 1.7907 -1.1176 180)
			(unlocked yes)
			(layer "F.Fab")
			(hide yes)
			(effects
				(font
					(size 1.016 1.016)
					(thickness 0.1524)
				)
			)
		)
		(property "Device Type" "R402H16"
			(at 1.7907 -2.6416 180)
			(unlocked yes)
			(layer "F.Fab")
			(hide yes)
			(effects
				(font
					(size 1.016 1.016)
					(thickness 0.1524)
				)
			)
		)
		(duplicate_pad_numbers_are_jumpers no)
		(fp_rect
			(start -0.381 0.8382)
			(end 0.381 -0.8382)
			(stroke
				(width 0)
				(type default)
			)
			(fill no)
			(layer "F.CrtYd")
		)
		(fp_rect
			(start -0.381 0.8382)
			(end 0.381 -0.8382)
			(stroke
				(width 0)
				(type default)
			)
			(fill no)
			(layer "F.Fab")
		)
		(pad "1" smd custom
			(at 0 -0.4318 180)
			(size 0.127 0.127)
			(layers "F.Cu" "F.Mask" "F.Paste")
			(net "P3V3_CPU")
			(options
				(clearance outline)
				(anchor circle)
			)
			(primitives
				(gr_poly
					(pts
						(arc
							(start -0.2032 -0.2794)
							(mid -0.239121 -0.264521)
							(end -0.254 -0.2286)
						)
						(arc
							(start -0.254 0.2286)
							(mid -0.239121 0.264521)
							(end -0.2032 0.2794)
						)
						(arc
							(start 0.2032 0.2794)
							(mid 0.239121 0.264521)
							(end 0.254 0.2286)
						)
						(arc
							(start 0.254 -0.2286)
							(mid 0.239121 -0.264521)
							(end 0.2032 -0.2794)
						)
					)
					(width 0)
					(fill yes)
				)
			)
		)
		(pad "2" smd custom
			(at 0 0.4318 180)
			(size 0.127 0.127)
			(layers "F.Cu" "F.Mask" "F.Paste")
			(net "MSATA_PRESENT_R#")
			(options
				(clearance outline)
				(anchor circle)
			)
			(primitives
				(gr_poly
					(pts
						(arc
							(start -0.2032 -0.2794)
							(mid -0.239121 -0.264521)
							(end -0.254 -0.2286)
						)
						(arc
							(start -0.254 0.2286)
							(mid -0.239121 0.264521)
							(end -0.2032 0.2794)
						)
						(arc
							(start 0.2032 0.2794)
							(mid 0.239121 0.264521)
							(end 0.254 0.2286)
						)
						(arc
							(start 0.254 -0.2286)
							(mid 0.239121 -0.264521)
							(end 0.2032 -0.2794)
						)
					)
					(width 0)
					(fill yes)
				)
			)
		)
	)
	(footprint ""
		(layer "F.Cu")
		(at 8.509 -55.626 90)
		(property "Reference" "C50"
			(at 0 0 90)
			(layer "F.SilkS")
			(hide yes)
			(effects
				(font
					(size 1.27 1.27)
				)
			)
		)
		(property "Value" "SCD1U16V2KX-3GP"
			(at 1.1811 -2.7051 90)
			(unlocked yes)
			(layer "F.Fab")
			(hide yes)
			(effects
				(font
					(size 1.016 1.016)
					(thickness 0.1524)
				)
			)
		)
		(property "Device Type" "C402H22"
			(at 1.1811 -4.2291 90)
			(unlocked yes)
			(layer "F.Fab")
			(hide yes)
			(effects
				(font
					(size 1.016 1.016)
					(thickness 0.1524)
				)
			)
		)
		(duplicate_pad_numbers_are_jumpers no)
		(fp_rect
			(start -0.381 0.7366)
			(end 0.381 -0.7366)
			(stroke
				(width 0)
				(type default)
			)
			(fill no)
			(layer "F.CrtYd")
		)
		(fp_rect
			(start -0.381 0.7366)
			(end 0.381 -0.7366)
			(stroke
				(width 0)
				(type default)
			)
			(fill no)
			(layer "F.Fab")
		)
		(pad "1" smd custom
			(at 0 -0.4572 90)
			(size 0.1143 0.1143)
			(layers "F.Cu" "F.Mask" "F.Paste")
			(net "P2E_CPU_NGFF_TX_DP13")
			(options
				(clearance outline)
				(anchor circle)
			)
			(primitives
				(gr_poly
					(pts
						(arc
							(start -0.254 -0.1778)
							(mid -0.239121 -0.213721)
							(end -0.2032 -0.2286)
						)
						(arc
							(start 0.2032 -0.2286)
							(mid 0.239121 -0.213721)
							(end 0.254 -0.1778)
						)
						(arc
							(start 0.254 0.1778)
							(mid 0.239121 0.213721)
							(end 0.2032 0.2286)
						)
						(arc
							(start -0.2032 0.2286)
							(mid -0.239121 0.213721)
							(end -0.254 0.1778)
						)
					)
					(width 0)
					(fill yes)
				)
			)
		)
		(pad "2" smd custom
			(at 0 0.4572 90)
			(size 0.1143 0.1143)
			(layers "F.Cu" "F.Mask" "F.Paste")
			(net "P2E_CPU_NGFF_C_TX_DP13")
			(options
				(clearance outline)
				(anchor circle)
			)
			(primitives
				(gr_poly
					(pts
						(arc
							(start -0.254 -0.1778)
							(mid -0.239121 -0.213721)
							(end -0.2032 -0.2286)
						)
						(arc
							(start 0.2032 -0.2286)
							(mid 0.239121 -0.213721)
							(end 0.254 -0.1778)
						)
						(arc
							(start 0.254 0.1778)
							(mid 0.239121 0.213721)
							(end 0.2032 0.2286)
						)
						(arc
							(start -0.2032 0.2286)
							(mid -0.239121 0.213721)
							(end -0.254 0.1778)
						)
					)
					(width 0)
					(fill yes)
				)
			)
		)
	)
	(footprint ""
		(layer "F.Cu")
		(at 27.4066 -63.246)
		(property "Reference" "PC62"
			(at 0 0 0)
			(layer "F.SilkS")
			(hide yes)
			(effects
				(font
					(size 1.27 1.27)
				)
			)
		)
		(property "Value" "SC10U16V6KX-2GP"
			(at 0.0127 -3.4671 0)
			(unlocked yes)
			(layer "F.Fab")
			(hide yes)
			(effects
				(font
					(size 1.016 1.016)
					(thickness 0.1524)
				)
			)
		)
		(property "Device Type" "C1206H71"
			(at 0.0127 -4.9911 0)
			(unlocked yes)
			(layer "F.Fab")
			(hide yes)
			(effects
				(font
					(size 1.016 1.016)
					(thickness 0.1524)
				)
			)
		)
		(duplicate_pad_numbers_are_jumpers no)
		(fp_rect
			(start -1.0541 1.9812)
			(end 1.0541 -1.9812)
			(stroke
				(width 0)
				(type default)
			)
			(fill no)
			(layer "F.CrtYd")
		)
		(fp_rect
			(start -1.0541 1.9812)
			(end 1.0541 -1.9812)
			(stroke
				(width 0)
				(type default)
			)
			(fill no)
			(layer "F.Fab")
		)
		(pad "1" smd rect
			(at 0 -1.3462)
			(size 1.8542 1.016)
			(layers "F.Cu" "F.Mask" "F.Paste")
			(net "VCCP_5VBIAS")
		)
		(pad "2" smd rect
			(at 0 1.3462)
			(size 1.8542 1.016)
			(layers "F.Cu" "F.Mask" "F.Paste")
			(net "GND")
		)
	)
)
